# BARRELEYE_G2-BPX24-EVT-HW-EBOM-X00_20161124-add_2nd_source_X09-20161207-Final.xls — DEPOP_GA (bom)
| FOXCONN TECHNOLOGY GROUP |  |  |  |  |  |  |  |  |  |  |  |  |
| BILL OF MATERIAL |  |  |  |  |  |  |  |  |  |  |  |  |
| REV OF  BOM |  | CUSTOMER | RACKSPACE |  | CUSTOMER P/N |  | PRODUCT CODE |  | PWA  REV |  | DATE |  |
| Sourcing (Single/Sole/Multi) | Critical Commodity (Y or N) | Component Class (1, 2, other) | Customer PSL (Y or N) | Item Number | Foxconn P/N | Customer P/N | Part Description | Manufacturer  Full Name | Manufacturer  Part Number | Qty | RoHS Status | Location |
